# TIMECARD (Time Appliance Project (Time Card)) — schematic netlist excerpt (pin names and nets, part order shuffled) for the footprints in the layout excerpt that follows; sources: Cadence DE-HDL packaged netlist, KiCad conversion of R4006-B0001-02_R01.brd

R137  RESISTOR  33OHM 1%  pkg SMC_0402R_H016  page 10 : \1\ = FT4232_FPGA_TDI ; \2\ = FPGA_TDI
R159  RESISTOR  4.7KOHM 1%  pkg SMC_0402R_H016  page 16 : \1\ = UNNAMED_5_24LC16BTISTTSSOP8_I15 ; \2\ = SG

(kicad_pcb
	(version 20260206)
	(generator "pcbnew")
	(generator_version "10.0")
	(general
		(thickness 1.6)
		(legacy_teardrops no)
	)
	(paper "A4")
	(title_block
		(title "timecard-production-celestica-r4006 — R4006-B0001-02_R01.brd")
		(comment 1 "Time Appliance Project (Time Card) / footprints 865-866 of 1113")
	)
	(layers
		(0 "F.Cu" signal "TOP")
		(4 "In1.Cu" signal "L02_GND1")
		(6 "In2.Cu" signal "L03_SIG1")
		(8 "In3.Cu" signal "L04_GND2")
		(10 "In4.Cu" signal "L05_VCC1")
		(12 "In5.Cu" signal "L06_VCC2")
		(14 "In6.Cu" signal "L07_GND3")
		(16 "In7.Cu" signal "L08_SIG2")
		(18 "In8.Cu" signal "L09_GND4")
		(2 "B.Cu" signal "BOTTOM")
		(9 "F.Adhes" user "F.Adhesive")
		(11 "B.Adhes" user "B.Adhesive")
		(13 "F.Paste" user "Package Geometry/Pastemask Top")
		(15 "B.Paste" user "Package Geometry/Pastemask Bottom")
		(5 "F.SilkS" user "Ref Des/Silkscreen Top")
		(7 "B.SilkS" user "Ref Des/Silkscreen Bottom")
		(1 "F.Mask" user "Board Geometry/Soldermask Top")
		(3 "B.Mask" user "Board Geometry/Soldermask Bottom")
		(17 "Dwgs.User" user "User.Drawings")
		(19 "Cmts.User" user "User.Comments")
		(21 "Eco1.User" user "User.Eco1")
		(23 "Eco2.User" user "User.Eco2")
		(25 "Edge.Cuts" user "Board Geometry/Outline")
		(27 "Margin" user)
		(31 "F.CrtYd" user "Package Geometry/Place Bound Top")
		(29 "B.CrtYd" user "Package Geometry/Place Bound Bottom")
		(35 "F.Fab" user "Ref Des/Assembly Top")
		(33 "B.Fab" user "Ref Des/Assembly Bottom")
	)
	(footprint ""
		(layer "B.Cu")
		(at 140.335 -76.708)
		(property "Reference" "R137"
			(at 0 -2.24663 0)
			(unlocked yes)
			(layer "B.SilkS")
			(effects
				(font
					(size 0.7874 0.5842)
					(thickness 0.1524)
				)
				(justify mirror)
			)
		)
		(property "Value" "VAL*"
			(at -0.02032 2.13233 0)
			(unlocked yes)
			(layer "B.Fab")
			(hide yes)
			(effects
				(font
					(size 0.7874 0.5842)
					(thickness 0.1524)
				)
				(justify mirror)
			)
		)
		(property "Tolerance" "TOL*"
			(at -0.044704 3.05435 0)
			(unlocked yes)
			(layer "Cmts.User")
			(hide yes)
			(effects
				(font
					(size 0.7874 0.5842)
					(thickness 0.1524)
				)
				(justify mirror)
			)
		)
		(property "User Part Number" "PARTNUM*"
			(at -0.02032 4.024884 0)
			(unlocked yes)
			(layer "Cmts.User")
			(hide yes)
			(effects
				(font
					(size 0.7874 0.5842)
					(thickness 0.1524)
				)
				(justify mirror)
			)
		)
		(property "Device Type" "RESISTOR-G155-133R0-01,33OHM,1%"
			(at -0.008382 1.210564 0)
			(unlocked yes)
			(layer "B.Fab")
			(hide yes)
			(effects
				(font
					(size 0.7874 0.5842)
					(thickness 0.1524)
				)
				(justify mirror)
			)
		)
		(duplicate_pad_numbers_are_jumpers no)
		(fp_line
			(start -1.143 -0.5588)
			(end 1.143 -0.5588)
			(stroke
				(width 0.1)
				(type default)
			)
			(layer "B.SilkS")
		)
		(fp_line
			(start -1.143 0.5588)
			(end -1.143 -0.5588)
			(stroke
				(width 0.1)
				(type default)
			)
			(layer "B.SilkS")
		)
		(fp_line
			(start 1.143 -0.5588)
			(end 1.143 0.5588)
			(stroke
				(width 0.1)
				(type default)
			)
			(layer "B.SilkS")
		)
		(fp_line
			(start 1.143 0.5588)
			(end -1.143 0.5588)
			(stroke
				(width 0.1)
				(type default)
			)
			(layer "B.SilkS")
		)
		(fp_rect
			(start 1.143 0.5588)
			(end -1.143 -0.5588)
			(stroke
				(width 0)
				(type default)
			)
			(fill no)
			(layer "B.CrtYd")
		)
		(fp_line
			(start -0.508 -0.3048)
			(end 0.508 -0.3048)
			(stroke
				(width 0.1)
				(type default)
			)
			(layer "B.Fab")
		)
		(fp_line
			(start -0.508 0.3048)
			(end -0.508 -0.3048)
			(stroke
				(width 0.1)
				(type default)
			)
			(layer "B.Fab")
		)
		(fp_line
			(start 0.508 -0.3048)
			(end 0.508 0.3048)
			(stroke
				(width 0.1)
				(type default)
			)
			(layer "B.Fab")
		)
		(fp_line
			(start 0.508 0.3048)
			(end -0.508 0.3048)
			(stroke
				(width 0.1)
				(type default)
			)
			(layer "B.Fab")
		)
		(pad "1" smd rect
			(at 0.5334 0 180)
			(size 0.7112 0.6096)
			(layers "B.Cu" "B.Mask" "B.Paste")
			(net "FT4232_FPGA_TDI")
		)
		(pad "2" smd rect
			(at -0.5334 0 180)
			(size 0.7112 0.6096)
			(layers "B.Cu" "B.Mask" "B.Paste")
			(net "FPGA_TDI")
		)
		(zone
			(layer "B.Cu")
			(hatch none 0.5)
			(connect_pads
				(clearance 0)
			)
			(min_thickness 0.25)
			(keepout
				(tracks allowed)
				(vias not_allowed)
				(pads allowed)
				(copperpour not_allowed)
				(footprints allowed)
			)
			(placement
				(enabled no)
				(sheetname "")
			)
			(fill
				(thermal_gap 0.5)
				(thermal_bridge_width 0.5)
				(island_removal_mode 0)
			)
			(polygon
				(pts
					(xy 140.4112 -76.4032) (xy 140.4112 -77.0128) (xy 140.2588 -77.0128) (xy 140.2588 -76.4032)
				)
			)
		)
	)
	(footprint ""
		(layer "B.Cu")
		(at 22.3012 -23.6728 90)
		(property "Reference" "R159"
			(at 2.6162 0.01143 270)
			(unlocked yes)
			(layer "B.SilkS")
			(effects
				(font
					(size 0.7874 0.5842)
					(thickness 0.1524)
				)
				(justify mirror)
			)
		)
		(property "Value" "VAL*"
			(at -0.02032 2.13233 90)
			(unlocked yes)
			(layer "B.Fab")
			(hide yes)
			(effects
				(font
					(size 0.7874 0.5842)
					(thickness 0.1524)
				)
				(justify mirror)
			)
		)
		(property "Tolerance" "TOL*"
			(at -0.044704 3.05435 90)
			(unlocked yes)
			(layer "Cmts.User")
			(hide yes)
			(effects
				(font
					(size 0.7874 0.5842)
					(thickness 0.1524)
				)
				(justify mirror)
			)
		)
		(property "User Part Number" "PARTNUM*"
			(at -0.02032 4.024884 90)
			(unlocked yes)
			(layer "Cmts.User")
			(hide yes)
			(effects
				(font
					(size 0.7874 0.5842)
					(thickness 0.1524)
				)
				(justify mirror)
			)
		)
		(property "Device Type" "RESISTOR-G155-14701-01,4.7KOHMA"
			(at -0.008382 1.210564 90)
			(unlocked yes)
			(layer "B.Fab")
			(hide yes)
			(effects
				(font
					(size 0.7874 0.5842)
					(thickness 0.1524)
				)
				(justify mirror)
			)
		)
		(duplicate_pad_numbers_are_jumpers no)
		(fp_line
			(start 1.143 -0.5588)
			(end 1.143 0.5588)
			(stroke
				(width 0.1)
				(type default)
			)
			(layer "B.SilkS")
		)
		(fp_line
			(start -1.143 -0.5588)
			(end 1.143 -0.5588)
			(stroke
				(width 0.1)
				(type default)
			)
			(layer "B.SilkS")
		)
		(fp_line
			(start 1.143 0.5588)
			(end -1.143 0.5588)
			(stroke
				(width 0.1)
				(type default)
			)
			(layer "B.SilkS")
		)
		(fp_line
			(start -1.143 0.5588)
			(end -1.143 -0.5588)
			(stroke
				(width 0.1)
				(type default)
			)
			(layer "B.SilkS")
		)
		(fp_rect
			(start 1.143 -0.5588)
			(end -1.143 0.5588)
			(stroke
				(width 0)
				(type default)
			)
			(fill no)
			(layer "B.CrtYd")
		)
		(fp_line
			(start 0.508 -0.3048)
			(end 0.508 0.3048)
			(stroke
				(width 0.1)
				(type default)
			)
			(layer "B.Fab")
		)
		(fp_line
			(start -0.508 -0.3048)
			(end 0.508 -0.3048)
			(stroke
				(width 0.1)
				(type default)
			)
			(layer "B.Fab")
		)
		(fp_line
			(start 0.508 0.3048)
			(end -0.508 0.3048)
			(stroke
				(width 0.1)
				(type default)
			)
			(layer "B.Fab")
		)
		(fp_line
			(start -0.508 0.3048)
			(end -0.508 -0.3048)
			(stroke
				(width 0.1)
				(type default)
			)
			(layer "B.Fab")
		)
		(pad "1" smd rect
			(at 0.5334 0 270)
			(size 0.7112 0.6096)
			(layers "B.Cu" "B.Mask" "B.Paste")
			(net "UNNAMED_5_24LC16BTISTTSSOP8_I15")
		)
		(pad "2" smd rect
			(at -0.5334 0 270)
			(size 0.7112 0.6096)
			(layers "B.Cu" "B.Mask" "B.Paste")
			(net "SG")
		)
		(zone
			(layer "B.Cu")
			(hatch none 0.5)
			(connect_pads
				(clearance 0)
			)
			(min_thickness 0.25)
			(keepout
				(tracks allowed)
				(vias not_allowed)
				(pads allowed)
				(copperpour not_allowed)
				(footprints allowed)
			)
			(placement
				(enabled no)
				(sheetname "")
			)
			(fill
				(thermal_gap 0.5)
				(thermal_bridge_width 0.5)
				(island_removal_mode 0)
			)
			(polygon
				(pts
					(xy 21.9964 -23.749) (xy 21.9964 -23.5966) (xy 22.606 -23.5966) (xy 22.606 -23.749)
				)
			)
		)
	)
)
